# T6G (Grand Teton) — schematic netlist excerpt (pin names and nets, part order shuffled) for the footprints in the layout excerpt that follows; sources: Cadence DE-HDL packaged netlist, KiCad conversion of 04192023_DAF0TMB3IC0_F0TG_MB_C_brd_V02_OCP.brd

C2567  Q_CAP  22UF 4V 20% X6S  pkg C0402  page 70 : A = PVDDCR_SOC_P0 ; B = GND
R6125  Q_RES  1K 1% EMPTY  pkg 0402LF  page 84 : A = FM_BOARD_SKU_ID4 ; B = GND

(kicad_pcb
	(version 20260206)
	(generator "pcbnew")
	(generator_version "10.0")
	(general
		(thickness 1.6)
		(legacy_teardrops no)
	)
	(paper "A4")
	(title_block
		(title "04192023_DAF0TMB3IC0_F0TG_MB_C_brd_V02_OCP.brd")
		(comment 1 "Grand Teton / footprints 8038-8039 of 8354")
	)
	(layers
		(0 "F.Cu" signal "TOP")
		(4 "In1.Cu" signal "GND")
		(6 "In2.Cu" signal "IN1")
		(8 "In3.Cu" signal "GND1")
		(10 "In4.Cu" signal "IN2")
		(12 "In5.Cu" signal "GND2")
		(14 "In6.Cu" signal "IN3")
		(16 "In7.Cu" signal "GND3")
		(18 "In8.Cu" signal "VCC")
		(20 "In9.Cu" signal "VCC1")
		(22 "In10.Cu" signal "GND4")
		(24 "In11.Cu" signal "IN4")
		(26 "In12.Cu" signal "GND5")
		(28 "In13.Cu" signal "IN5")
		(30 "In14.Cu" signal "GND6")
		(32 "In15.Cu" signal "IN6")
		(34 "In16.Cu" signal "GND7")
		(2 "B.Cu" signal "BOTTOM")
		(9 "F.Adhes" user "F.Adhesive")
		(11 "B.Adhes" user "B.Adhesive")
		(13 "F.Paste" user "Package Geometry/Pastemask Top")
		(15 "B.Paste" user "Package Geometry/Pastemask Bottom")
		(5 "F.SilkS" user "Ref Des/Silkscreen Top")
		(7 "B.SilkS" user "Ref Des/Silkscreen Bottom")
		(1 "F.Mask" user "Board Geometry/Soldermask Top")
		(3 "B.Mask" user "Board Geometry/Soldermask Bottom")
		(17 "Dwgs.User" user "User.Drawings")
		(19 "Cmts.User" user "User.Comments")
		(21 "Eco1.User" user "User.Eco1")
		(23 "Eco2.User" user "User.Eco2")
		(25 "Edge.Cuts" user "Board Geometry/Outline")
		(27 "Margin" user)
		(31 "F.CrtYd" user "Package Geometry/Place Bound Top")
		(29 "B.CrtYd" user "Package Geometry/Place Bound Bottom")
		(35 "F.Fab" user "Ref Des/Assembly Top")
		(33 "B.Fab" user "Ref Des/Assembly Bottom")
	)
	(footprint ""
		(layer "B.Cu")
		(at 350.199198 -252.224032 60)
		(property "Reference" "C2567"
			(at 0 0 60)
			(layer "B.SilkS")
			(hide yes)
			(effects
				(font
					(size 1.27 1.27)
				)
				(justify mirror)
			)
		)
		(property "Value" ""
			(at 0 0 60)
			(layer "B.Fab")
			(effects
				(font
					(size 1.27 1.27)
				)
				(justify mirror)
			)
		)
		(duplicate_pad_numbers_are_jumpers no)
		(fp_line
			(start -0.787516 -0.406438)
			(end -0.787425 0.40652)
			(stroke
				(width 0.1524)
				(type default)
			)
			(layer "B.SilkS")
		)
		(fp_line
			(start -0.787425 0.40652)
			(end 0.787516 0.406438)
			(stroke
				(width 0.1524)
				(type default)
			)
			(layer "B.SilkS")
		)
		(fp_line
			(start 0.787425 -0.40652)
			(end -0.787516 -0.406438)
			(stroke
				(width 0.1524)
				(type default)
			)
			(layer "B.SilkS")
		)
		(fp_line
			(start 0.787516 0.406438)
			(end 0.787425 -0.40652)
			(stroke
				(width 0.1524)
				(type default)
			)
			(layer "B.SilkS")
		)
		(fp_line
			(start -0.679568 -0.304811)
			(end -0.6795 0.304908)
			(stroke
				(width 0.1)
				(type default)
			)
			(layer "B.Fab")
		)
		(fp_line
			(start -0.120605 -0.304905)
			(end -0.679568 -0.304811)
			(stroke
				(width 0.1)
				(type default)
			)
			(layer "B.Fab")
		)
		(fp_line
			(start -0.120554 -0.279418)
			(end -0.120605 -0.304905)
			(stroke
				(width 0.1)
				(type default)
			)
			(layer "B.Fab")
		)
		(fp_line
			(start 0.120629 -0.30516)
			(end 0.120587 -0.279326)
			(stroke
				(width 0.1)
				(type default)
			)
			(layer "B.Fab")
		)
		(fp_line
			(start 0.120587 -0.279326)
			(end -0.120554 -0.279418)
			(stroke
				(width 0.1)
				(type default)
			)
			(layer "B.Fab")
		)
		(fp_line
			(start -0.6795 0.304908)
			(end -0.120316 0.304686)
			(stroke
				(width 0.1)
				(type default)
			)
			(layer "B.Fab")
		)
		(fp_line
			(start 0.679373 -0.305128)
			(end 0.120629 -0.30516)
			(stroke
				(width 0.1)
				(type default)
			)
			(layer "B.Fab")
		)
		(fp_line
			(start -0.12024 0.279419)
			(end 0.120554 0.279418)
			(stroke
				(width 0.1)
				(type default)
			)
			(layer "B.Fab")
		)
		(fp_line
			(start -0.120316 0.304686)
			(end -0.12024 0.279419)
			(stroke
				(width 0.1)
				(type default)
			)
			(layer "B.Fab")
		)
		(fp_line
			(start 0.120554 0.279418)
			(end 0.120605 0.304905)
			(stroke
				(width 0.1)
				(type default)
			)
			(layer "B.Fab")
		)
		(fp_line
			(start 0.120605 0.304905)
			(end 0.679568 0.304811)
			(stroke
				(width 0.1)
				(type default)
			)
			(layer "B.Fab")
		)
		(fp_line
			(start 0.679568 0.304811)
			(end 0.679373 -0.305128)
			(stroke
				(width 0.1)
				(type default)
			)
			(layer "B.Fab")
		)
		(pad "1" smd circle
			(at 0.40005 0 240)
			(size 0 0)
			(layers "B.Cu" "B.Mask" "B.Paste")
			(net "PVDDCR_SOC_P0")
		)
		(pad "2" smd circle
			(at -0.40005 0 240)
			(size 0 0)
			(layers "B.Cu" "B.Mask" "B.Paste")
			(net "GND")
		)
	)
	(footprint ""
		(layer "B.Cu")
		(at 405.809196 -354.439728 -90)
		(property "Reference" "R6125"
			(at 0 0 90)
			(layer "B.SilkS")
			(hide yes)
			(effects
				(font
					(size 1.27 1.27)
				)
				(justify mirror)
			)
		)
		(property "Value" ""
			(at 0 0 90)
			(layer "B.Fab")
			(effects
				(font
					(size 1.27 1.27)
				)
				(justify mirror)
			)
		)
		(duplicate_pad_numbers_are_jumpers no)
		(fp_line
			(start -0.7874 0.4064)
			(end 0.7874 0.4064)
			(stroke
				(width 0.1524)
				(type default)
			)
			(layer "B.SilkS")
		)
		(fp_line
			(start 0.7874 0.4064)
			(end 0.7874 -0.4064)
			(stroke
				(width 0.1524)
				(type default)
			)
			(layer "B.SilkS")
		)
		(fp_line
			(start -0.7874 -0.4064)
			(end -0.7874 0.4064)
			(stroke
				(width 0.1524)
				(type default)
			)
			(layer "B.SilkS")
		)
		(fp_line
			(start 0.7874 -0.4064)
			(end -0.7874 -0.4064)
			(stroke
				(width 0.1524)
				(type default)
			)
			(layer "B.SilkS")
		)
		(fp_line
			(start -0.67945 0.3048)
			(end -0.120396 0.3048)
			(stroke
				(width 0.1)
				(type default)
			)
			(layer "B.Fab")
		)
		(fp_line
			(start -0.120396 0.3048)
			(end -0.120396 0.2794)
			(stroke
				(width 0.1)
				(type default)
			)
			(layer "B.Fab")
		)
		(fp_line
			(start 0.12065 0.3048)
			(end 0.67945 0.3048)
			(stroke
				(width 0.1)
				(type default)
			)
			(layer "B.Fab")
		)
		(fp_line
			(start 0.67945 0.3048)
			(end 0.67945 -0.305054)
			(stroke
				(width 0.1)
				(type default)
			)
			(layer "B.Fab")
		)
		(fp_line
			(start -0.120396 0.2794)
			(end 0.12065 0.2794)
			(stroke
				(width 0.1)
				(type default)
			)
			(layer "B.Fab")
		)
		(fp_line
			(start 0.12065 0.2794)
			(end 0.12065 0.3048)
			(stroke
				(width 0.1)
				(type default)
			)
			(layer "B.Fab")
		)
		(fp_line
			(start -0.12065 -0.2794)
			(end -0.12065 -0.3048)
			(stroke
				(width 0.1)
				(type default)
			)
			(layer "B.Fab")
		)
		(fp_line
			(start 0.12065 -0.2794)
			(end -0.12065 -0.2794)
			(stroke
				(width 0.1)
				(type default)
			)
			(layer "B.Fab")
		)
		(fp_line
			(start -0.67945 -0.3048)
			(end -0.67945 0.3048)
			(stroke
				(width 0.1)
				(type default)
			)
			(layer "B.Fab")
		)
		(fp_line
			(start -0.12065 -0.3048)
			(end -0.67945 -0.3048)
			(stroke
				(width 0.1)
				(type default)
			)
			(layer "B.Fab")
		)
		(fp_line
			(start 0.12065 -0.305054)
			(end 0.12065 -0.2794)
			(stroke
				(width 0.1)
				(type default)
			)
			(layer "B.Fab")
		)
		(fp_line
			(start 0.67945 -0.305054)
			(end 0.12065 -0.305054)
			(stroke
				(width 0.1)
				(type default)
			)
			(layer "B.Fab")
		)
		(pad "1" smd circle
			(at 0.40005 0 90)
			(size 0 0)
			(layers "B.Cu" "B.Mask" "B.Paste")
			(net "FM_BOARD_SKU_ID4")
		)
		(pad "2" smd circle
			(at -0.40005 0 90)
			(size 0 0)
			(layers "B.Cu" "B.Mask" "B.Paste")
			(net "GND")
		)
	)
)
